FILE_TYPE = MACRO_DRAWING;
SET COLOR_WIRE YELLOW;
SET COLOR_PROP ORANGE;
SET COLOR_DOT WHITE;
SET COLOR_ARC YELLOW;
SET COLOR_BODY GREEN;
SET COLOR_NOTE PURPLE;
SET PROP_DISPLAY VALUE;
SET PAGE_NUMBER P453;
FORCEADD OFFPAGE..1
(-7525 5575);
FORCEPROP 2 LAST $XR1 186 
J 0
(-7897 5575);
DISPLAY 0.638298 (-7897 5575);
PAINT MONO (-7897 5575);
FORCEPROP 2 LAST $XR0 185 
J 0
(-7777 5575);
DISPLAY 0.638298 (-7777 5575);
PAINT MONO (-7777 5575);
FORCEPROP 2 LAST CDS_LIB standard
J 0
(-7525 5575);
DISPLAY INVISIBLE (-7525 5575);
FORCEPROP 1 LAST OFFPAGE TRUE
J 0
(-7200 5450);
DISPLAY 0.872340 (-7200 5450);
DISPLAY INVISIBLE (-7200 5450);
FORCEPROP 1 LAST COMMENT_BODY TRUE
J 0
(-7400 5475);
DISPLAY 0.872340 (-7400 5475);
PAINT GREEN (-7400 5475);
DISPLAY INVISIBLE (-7400 5475);
FORCEPROP 2 LAST PATH I1
J 0
(-7475 5650);
DISPLAY 0.680851 (-7475 5650);
DISPLAY INVISIBLE (-7475 5650);
FORCEADD UNIVERSAL_GND..1
(-4050 5350);
FORCEPROP 3 LASTPIN (-4050 5400) SIG_NAME GND\g
J 0
(-4040 5410);
DISPLAY 0.659574 (-4040 5410);
PAINT MONO (-4040 5410);
DISPLAY INVISIBLE (-4040 5410);
FORCEPROP 2 LAST CDS_LIB pure_quanta_power
J 0
(-4050 5350);
DISPLAY INVISIBLE (-4050 5350);
FORCEPROP 1 LAST HDL_POWER GND
J 1
(-4025 5275);
DISPLAY 0.872340 (-4025 5275);
PAINT GREEN (-4025 5275);
DISPLAY INVISIBLE (-4025 5275);
FORCEPROP 1 LAST PATH I18
J 0
(-3975 5350);
DISPLAY 0.872340 (-3975 5350);
PAINT AQUA (-3975 5350);
DISPLAY INVISIBLE (-3975 5350);
FORCEADD Q_RES..2
(-3900 5425);
FORCEPROP 1 LAST LOCATION R6790
J 0
(-3855 5550);
DISPLAY 0.978723 (-3855 5550);
FORCEPROP 0 LAST $SEC 1
J 0
(-3850 5600);
DISPLAY 0.680851 (-3850 5600);
PAINT MONO (-3850 5600);
DISPLAY INVISIBLE (-3850 5600);
FORCEPROP 0 LAST CDS_SEC 1
J 0
(-3850 5600);
DISPLAY 0.680851 (-3850 5600);
DISPLAY INVISIBLE (-3850 5600);
FORCEPROP 1 LASTPIN (-3900 5525) $PN 1
J 0
(-3895 5487);
DISPLAY 0.787234 (-3895 5487);
PAINT MONO (-3895 5487);
FORCEPROP 1 LASTPIN (-3900 5325) $PN 2
J 0
(-3895 5335);
DISPLAY 0.787234 (-3895 5335);
PAINT MONO (-3895 5335);
FORCEPROP 1 LAST WATTAGE 1/20W
J 0
(-3860 5400);
DISPLAY 0.978723 (-3860 5400);
FORCEPROP 1 LAST TOLERANCE 1%
J 0
(-3855 5450);
DISPLAY 0.978723 (-3855 5450);
FORCEPROP 1 LAST VALUE 1K
J 0
(-3855 5500);
DISPLAY 0.978723 (-3855 5500);
FORCEPROP 1 LAST MATERIAL CHIP
J 0
(-3860 5350);
DISPLAY 0.978723 (-3860 5350);
FORCEPROP 1 LAST PACK_TYPE 0201LF
J 0
(-3860 5250);
DISPLAY 0.978723 (-3860 5250);
FORCEPROP 2 LAST CDS_LIB pure_quanta
J 0
(-3900 5425);
DISPLAY INVISIBLE (-3900 5425);
FORCEPROP 1 LAST PATH I19
J 0
(-3850 5600);
DISPLAY 0.978723 (-3850 5600);
PAINT WHITE (-3850 5600);
DISPLAY INVISIBLE (-3850 5600);
FORCEPROP 1 LAST PART_NUMBER CS21001FE07
J 0
(-3860 5300);
DISPLAY 0.978723 (-3860 5300);
DISPLAY INVISIBLE (-3860 5300);
FORCEADD OFFPAGE..3
R 2
(-7500 5525);
FORCEPROP 2 LAST $XR1 186 
J 0
(-7930 5525);
DISPLAY 0.638298 (-7930 5525);
PAINT MONO (-7930 5525);
FORCEPROP 2 LAST $XR0 185 
J 0
(-7810 5525);
DISPLAY 0.638298 (-7810 5525);
PAINT MONO (-7810 5525);
FORCEPROP 2 LAST CDS_LIB standard
J 0
(-7500 5525);
DISPLAY INVISIBLE (-7500 5525);
FORCEPROP 1 LAST OFFPAGE TRUE
J 2
(-7825 5400);
DISPLAY 0.872340 (-7825 5400);
PAINT GREEN (-7825 5400);
DISPLAY INVISIBLE (-7825 5400);
FORCEPROP 1 LAST COMMENT_BODY TRUE
J 2
(-7450 5425);
DISPLAY 0.872340 (-7450 5425);
PAINT GREEN (-7450 5425);
DISPLAY INVISIBLE (-7450 5425);
FORCEPROP 2 LAST PATH I2
J 0
(-7450 5600);
DISPLAY 0.680851 (-7450 5600);
DISPLAY INVISIBLE (-7450 5600);
FORCEADD UNIVERSAL_GND..1
(-3900 5075);
FORCEPROP 3 LASTPIN (-3900 5125) SIG_NAME GND\g
J 0
(-3890 5135);
DISPLAY 0.659574 (-3890 5135);
PAINT MONO (-3890 5135);
DISPLAY INVISIBLE (-3890 5135);
FORCEPROP 2 LAST CDS_LIB pure_quanta_power
J 0
(-3900 5075);
DISPLAY INVISIBLE (-3900 5075);
FORCEPROP 1 LAST HDL_POWER GND
J 1
(-3875 5000);
DISPLAY 0.872340 (-3875 5000);
PAINT GREEN (-3875 5000);
DISPLAY INVISIBLE (-3875 5000);
FORCEPROP 1 LAST PATH I20
J 0
(-3825 5075);
DISPLAY 0.872340 (-3825 5075);
PAINT AQUA (-3825 5075);
DISPLAY INVISIBLE (-3825 5075);
FORCEADD UNIVERSAL_GND..1
R 7
(-5325 5625);
FORCEPROP 3 LASTPIN (-5275 5625) SIG_NAME GND\g
J 0
(-5265 5635);
DISPLAY 0.659574 (-5265 5635);
PAINT MONO (-5265 5635);
DISPLAY INVISIBLE (-5265 5635);
FORCEPROP 2 LAST CDS_LIB pure_quanta_power
J 0
(-5325 5625);
DISPLAY INVISIBLE (-5325 5625);
FORCEPROP 1 LAST HDL_POWER GND
R 1
J 1
(-5400 5650);
DISPLAY 0.872340 (-5400 5650);
PAINT GREEN (-5400 5650);
DISPLAY INVISIBLE (-5400 5650);
FORCEPROP 1 LAST PATH I21
R 1
J 0
(-5325 5700);
DISPLAY 0.872340 (-5325 5700);
PAINT AQUA (-5325 5700);
DISPLAY INVISIBLE (-5325 5700);
FORCEADD P1V0..1
(-5300 6350);
FORCEPROP 3 LASTPIN (-5300 6300) SIG_NAME P1V8_CPU1_RT_1D\g
J 0
(-5290 6310);
DISPLAY 0.659574 (-5290 6310);
PAINT MONO (-5290 6310);
DISPLAY INVISIBLE (-5290 6310);
FORCEPROP 1 LAST HDL_POWER P1V8_CPU1_RT_1D
J 1
(-5300 6400);
DISPLAY 0.489362 (-5300 6400);
PAINT SKYBLUE (-5300 6400);
FORCEPROP 2 LAST CDS_LIB pure_quanta_power
J 0
(-5300 6350);
DISPLAY INVISIBLE (-5300 6350);
FORCEPROP 1 LAST PATH I22
J 0
(-5250 6375);
DISPLAY 0.872340 (-5250 6375);
PAINT AQUA (-5250 6375);
DISPLAY INVISIBLE (-5250 6375);
FORCEADD Q_CAP..1
(-5600 6025);
FORCEPROP 1 LAST LOCATION C7503
J 0
(-5550 6125);
DISPLAY 0.787234 (-5550 6125);
PAINT SKYBLUE (-5550 6125);
FORCEPROP 0 LAST $SEC 1
J 0
(-5550 6175);
DISPLAY 0.680851 (-5550 6175);
PAINT MONO (-5550 6175);
DISPLAY INVISIBLE (-5550 6175);
FORCEPROP 0 LAST CDS_SEC 1
J 0
(-5550 6175);
DISPLAY 0.680851 (-5550 6175);
DISPLAY INVISIBLE (-5550 6175);
FORCEPROP 1 LASTPIN (-5600 6125) $PN 1
J 0
(-5590 6105);
DISPLAY 0.787234 (-5590 6105);
PAINT MONO (-5590 6105);
FORCEPROP 1 LASTPIN (-5600 5925) $PN 2
J 0
(-5590 5905);
DISPLAY 0.787234 (-5590 5905);
PAINT MONO (-5590 5905);
FORCEPROP 1 LAST MATERIAL X7S
J 0
(-5550 5925);
DISPLAY 0.510638 (-5550 5925);
FORCEPROP 1 LAST PACK_TYPE C0201
J 0
(-5550 5875);
DISPLAY 0.510638 (-5550 5875);
FORCEPROP 1 LAST VALUE 0.1UF
J 0
(-5550 6075);
DISPLAY 0.510638 (-5550 6075);
FORCEPROP 1 LAST TOLERANCE 10%
J 0
(-5550 5975);
DISPLAY 0.510638 (-5550 5975);
FORCEPROP 1 LAST VOLTAGE 10V
J 0
(-5550 6025);
DISPLAY 0.510638 (-5550 6025);
FORCEPROP 2 LAST CDS_LIB pure_quanta
J 0
(-5600 6025);
DISPLAY INVISIBLE (-5600 6025);
FORCEPROP 1 LAST PATH I23
J 0
(-5550 6175);
DISPLAY 0.978723 (-5550 6175);
PAINT WHITE (-5550 6175);
DISPLAY INVISIBLE (-5550 6175);
FORCEPROP 1 LAST PART_NUMBER CH4102K6E00
J 0
(-5550 5875);
DISPLAY 0.978723 (-5550 5875);
DISPLAY INVISIBLE (-5550 5875);
FORCEADD UNIVERSAL_GND..1
(-5600 5825);
FORCEPROP 3 LASTPIN (-5600 5875) SIG_NAME GND\g
J 0
(-5590 5885);
DISPLAY 0.659574 (-5590 5885);
PAINT MONO (-5590 5885);
DISPLAY INVISIBLE (-5590 5885);
FORCEPROP 2 LAST CDS_LIB pure_quanta_power
J 0
(-5600 5825);
DISPLAY INVISIBLE (-5600 5825);
FORCEPROP 1 LAST HDL_POWER GND
J 1
(-5575 5750);
DISPLAY 0.872340 (-5575 5750);
PAINT GREEN (-5575 5750);
DISPLAY INVISIBLE (-5575 5750);
FORCEPROP 1 LAST PATH I24
J 0
(-5525 5825);
DISPLAY 0.872340 (-5525 5825);
PAINT AQUA (-5525 5825);
DISPLAY INVISIBLE (-5525 5825);
FORCEADD Q_RES..1
(-6300 5525);
FORCEPROP 1 LAST LOCATION R694
J 0
(-6550 5525);
DISPLAY 0.978723 (-6550 5525);
FORCEPROP 0 LAST $SEC 1
J 0
(-6550 5575);
DISPLAY 0.680851 (-6550 5575);
PAINT MONO (-6550 5575);
DISPLAY INVISIBLE (-6550 5575);
FORCEPROP 0 LAST CDS_SEC 1
J 0
(-6550 5575);
DISPLAY 0.680851 (-6550 5575);
DISPLAY INVISIBLE (-6550 5575);
FORCEPROP 1 LASTPIN (-6400 5525) $PN 1
J 0
(-6388 5537);
DISPLAY 0.787234 (-6388 5537);
PAINT MONO (-6388 5537);
FORCEPROP 1 LASTPIN (-6200 5525) $PN 2
J 0
(-6238 5537);
DISPLAY 0.787234 (-6238 5537);
PAINT MONO (-6238 5537);
FORCEPROP 1 LAST MATERIAL CHIP
J 0
(-6475 5600);
DISPLAY 0.787234 (-6475 5600);
DISPLAY INVISIBLE (-6475 5600);
FORCEPROP 2 LAST CDS_LIB pure_quanta
J 0
(-6300 5525);
DISPLAY INVISIBLE (-6300 5525);
FORCEPROP 1 LAST WATTAGE 1/20W
J 2
(-6500 5600);
DISPLAY 0.787234 (-6500 5600);
DISPLAY INVISIBLE (-6500 5600);
FORCEPROP 1 LAST PACK_TYPE 0201LF
J 0
(-6275 5600);
DISPLAY 0.787234 (-6275 5600);
DISPLAY INVISIBLE (-6275 5600);
FORCEPROP 1 LAST VALUE 33.2
J 2
(-6500 5650);
DISPLAY 0.787234 (-6500 5650);
DISPLAY INVISIBLE (-6500 5650);
FORCEPROP 1 LAST TOLERANCE 1%
J 0
(-6475 5650);
DISPLAY 0.787234 (-6475 5650);
DISPLAY INVISIBLE (-6475 5650);
FORCEPROP 1 LAST PATH I3
J 0
(-6350 5675);
DISPLAY 0.978723 (-6350 5675);
PAINT WHITE (-6350 5675);
DISPLAY INVISIBLE (-6350 5675);
FORCEPROP 1 LAST PART_NUMBER CS03321FE09
J 0
(-6350 5650);
DISPLAY 0.808511 (-6350 5650);
DISPLAY INVISIBLE (-6350 5650);
FORCEADD Q_RES..1
(-6300 5575);
FORCEPROP 1 LAST LOCATION R693
J 0
(-6550 5575);
DISPLAY 0.978723 (-6550 5575);
FORCEPROP 0 LAST $SEC 1
J 0
(-6350 5750);
DISPLAY 0.680851 (-6350 5750);
PAINT MONO (-6350 5750);
DISPLAY INVISIBLE (-6350 5750);
FORCEPROP 0 LAST CDS_SEC 1
J 0
(-6350 5750);
DISPLAY 0.680851 (-6350 5750);
DISPLAY INVISIBLE (-6350 5750);
FORCEPROP 1 LASTPIN (-6400 5575) $PN 1
J 0
(-6388 5587);
DISPLAY 0.787234 (-6388 5587);
PAINT MONO (-6388 5587);
FORCEPROP 1 LASTPIN (-6200 5575) $PN 2
J 0
(-6238 5587);
DISPLAY 0.787234 (-6238 5587);
PAINT MONO (-6238 5587);
FORCEPROP 1 LAST MATERIAL CHIP
J 0
(-6475 5650);
DISPLAY 0.787234 (-6475 5650);
FORCEPROP 1 LAST WATTAGE 1/20W
J 2
(-6500 5650);
DISPLAY 0.787234 (-6500 5650);
FORCEPROP 1 LAST PACK_TYPE 0201LF
J 0
(-6275 5650);
DISPLAY 0.787234 (-6275 5650);
FORCEPROP 1 LAST VALUE 33.2
J 2
(-6500 5700);
DISPLAY 0.787234 (-6500 5700);
FORCEPROP 1 LAST TOLERANCE 1%
J 0
(-6475 5700);
DISPLAY 0.787234 (-6475 5700);
FORCEPROP 2 LAST CDS_LIB pure_quanta
J 0
(-6300 5575);
DISPLAY INVISIBLE (-6300 5575);
FORCEPROP 1 LAST PATH I4
J 0
(-6350 5725);
DISPLAY 0.978723 (-6350 5725);
PAINT WHITE (-6350 5725);
DISPLAY INVISIBLE (-6350 5725);
FORCEPROP 1 LAST PART_NUMBER CS03321FE09
J 0
(-6350 5700);
DISPLAY 0.808511 (-6350 5700);
DISPLAY INVISIBLE (-6350 5700);
FORCEADD M24M02DRMN6TP..1
(-4875 5600);
FORCEPROP 1 LAST LOCATION U20
J 0
(-5069 5940);
DISPLAY 0.723404 (-5069 5940);
PAINT GREEN (-5069 5940);
FORCEPROP 0 LAST $SEC 1
J 0
(-5050 6075);
DISPLAY 0.680851 (-5050 6075);
PAINT MONO (-5050 6075);
DISPLAY INVISIBLE (-5050 6075);
FORCEPROP 0 LAST CDS_SEC 1
J 0
(-5050 6075);
DISPLAY 0.680851 (-5050 6075);
DISPLAY INVISIBLE (-5050 6075);
FORCEPROP 0 LASTPIN (-4550 5675) $PN 1
J 0
(-4540 5685);
DISPLAY 0.680851 (-4540 5685);
PAINT MONO (-4540 5685);
FORCEPROP 0 LASTPIN (-4550 5625) $PN 2
J 0
(-4540 5635);
DISPLAY 0.680851 (-4540 5635);
PAINT MONO (-4540 5635);
FORCEPROP 0 LASTPIN (-4550 5575) $PN 3
J 0
(-4540 5585);
DISPLAY 0.680851 (-4540 5585);
PAINT MONO (-4540 5585);
FORCEPROP 0 LASTPIN (-5200 5575) $PN 6
J 2
(-5210 5585);
DISPLAY 0.680851 (-5210 5585);
PAINT MONO (-5210 5585);
FORCEPROP 0 LASTPIN (-5200 5525) $PN 5
J 2
(-5210 5535);
DISPLAY 0.680851 (-5210 5535);
PAINT MONO (-5210 5535);
FORCEPROP 0 LASTPIN (-5200 5675) $PN 8
J 2
(-5210 5685);
DISPLAY 0.680851 (-5210 5685);
PAINT MONO (-5210 5685);
FORCEPROP 0 LASTPIN (-4550 5525) $PN 4
J 0
(-4540 5535);
DISPLAY 0.680851 (-4540 5535);
PAINT MONO (-4540 5535);
FORCEPROP 0 LASTPIN (-5200 5625) $PN 7
J 2
(-5210 5635);
DISPLAY 0.680851 (-5210 5635);
PAINT MONO (-5210 5635);
FORCEPROP 1 LAST MATERIAL IC
J 0
(-5069 5732);
DISPLAY 0.723404 (-5069 5732);
PAINT GREEN (-5069 5732);
FORCEPROP 2 LAST PART_TYPE SMLF
J 0
(-5050 6025);
DISPLAY 0.680851 (-5050 6025);
FORCEPROP 2 LAST VALUE M24M02-DRMN6TP
J 0
(-5050 5975);
DISPLAY 0.680851 (-5050 5975);
FORCEPROP 1 LAST NEEDS_NO_SIZE TRUE
J 0
(-4700 5532);
DISPLAY 0.723404 (-4700 5532);
PAINT GREEN (-4700 5532);
DISPLAY INVISIBLE (-4700 5532);
FORCEPROP 1 LAST CDS_LMAN_SYM_OUTLINE -175,125,175,-125
J 0
(-4875 5600);
DISPLAY 0.468085 (-4875 5600);
PAINT GREEN (-4875 5600);
DISPLAY INVISIBLE (-4875 5600);
FORCEPROP 2 LAST CDS_LIB pure_quanta
J 0
(-4875 5600);
DISPLAY INVISIBLE (-4875 5600);
FORCEPROP 1 LAST PATH I5
J 0
(-4700 5475);
DISPLAY 0.723404 (-4700 5475);
PAINT GREEN (-4700 5475);
DISPLAY INVISIBLE (-4700 5475);
FORCEPROP 1 LAST PART_NUMBER AKE33Z00600
J 0
(-5069 5826);
DISPLAY 0.723404 (-5069 5826);
PAINT GREEN (-5069 5826);
DISPLAY INVISIBLE (-5069 5826);
FORCEADD QUANTA_TITLE_BLOCK_C..1
(0 0);
FORCEPROP 0 LAST CDS_CON_LAST_MODIFIED Thu Sep 14 16:13:00 2023
J 0
(-1885 15);
DISPLAY INVISIBLE (-1885 15);
FORCEPROP 1 LAST CUSTOM_TXT_CDS <CON_LAST_MODIFIED>
J 0
(-1885 15);
DISPLAY 0.978723 (-1885 15);
FORCEPROP 2 LAST CUSTOM_TXT_CDS <XR_PAGE_TITLE>
J 0
(-7890 5250);
DISPLAY 0.638298 (-7890 5250);
PAINT PINK (-7890 5250);
DISPLAY INVISIBLE (-7890 5250);
FORCEPROP 1 LAST CUSTOM_TXT_CDS <NAME_2>
J 0
(-3175 50);
FORCEPROP 1 LAST CUSTOM_TXT_CDS <NAME_1>
J 0
(-3175 175);
FORCEPROP 1 LAST CUSTOM_TXT_CDS <Q_NUMBER>
J 0
(-1403 103);
DISPLAY 1.212766 (-1403 103);
FORCEPROP 1 LAST CUSTOM_TXT_CDS <Q_PROJ>
J 0
(-2382 102);
DISPLAY 1.212766 (-2382 102);
FORCEPROP 1 LAST CUSTOM_TXT_CDS <Q_REV>
J 0
(-184 103);
DISPLAY 1.212766 (-184 103);
FORCEPROP 1 LAST CUSTOM_TXT_CDS <CON_PAGE_NUM> OF <CON_TOTAL_PAGES>
J 0
(-446 18);
DISPLAY 0.978723 (-446 18);
FORCEPROP 1 LAST Q_TITLE RETIMER_CPU1_P2(7)
J 0
(-9366 26);
DISPLAY 2.446809 (-9366 26);
PAINT GREEN (-9366 26);
FORCEPROP 2 LAST CDS_LIB pure_quanta
J 0
(0 0);
DISPLAY INVISIBLE (0 0);
FORCEPROP 1 LAST CDS_LMAN_SYM_OUTLINE -9475,6775,100,-125
J 0
(0 0);
DISPLAY 0.468085 (0 0);
PAINT GREEN (0 0);
DISPLAY INVISIBLE (0 0);
FORCEPROP 2 LAST PAGE_BORDER TRUE
J 0
(-7890 5250);
DISPLAY 0.638298 (-7890 5250);
PAINT PINK (-7890 5250);
DISPLAY INVISIBLE (-7890 5250);
FORCEPROP 2 LAST CDS_XR_PAGE_TITLE CR-345 : @T6G_MB_LIB.T6G(SCH_1):PAGE345
J 0
(-7890 5250);
DISPLAY 0.638298 (-7890 5250);
PAINT PINK (-7890 5250);
DISPLAY INVISIBLE (-7890 5250);
FORCEPROP 1 LAST Q_DEPT BU9
J 1
(-3763 49);
DISPLAY 1.957447 (-3763 49);
PAINT GREEN (-3763 49);
DISPLAY INVISIBLE (-3763 49);
FORCEPROP 1 LAST COMMENT_BODY TRUE
J 0
(12 -13);
DISPLAY 0.978723 (12 -13);
PAINT GREEN (12 -13);
DISPLAY INVISIBLE (12 -13);
WIRE 16 -1 (-4550 5525)(-4050 5525);
WIRE 16 -1 (-4050 5525)(-4050 5400);
WIRE 16 -1 (-3900 5325)(-3900 5125);
WIRE 16 -1 (-5200 5625)(-5275 5625);
WIRE 16 -1 (-5600 5925)(-5600 5875);
WIRE 16 -1 (-6400 5575)(-7475 5575);
FORCEPROP 2 LAST SIG_NAME SMB_RT_CPU1_P2_ROM_R_SCL
J 0
(-7360 5585);
DISPLAY 0.680851 (-7360 5585);
WIRE 16 -1 (-5200 5575)(-6200 5575);
FORCEPROP 2 LAST SIG_NAME SMB_RT_CPU1_P2_ROM_SCL
J 0
(-6085 5585);
DISPLAY 0.680851 (-6085 5585);
FORCEPROP 2 LASTPROP $XRERR UNIQUE?
J 0
(-6325 5585);
DISPLAY 0.638298 (-6325 5585);
PAINT MONO (-6325 5585);
DISPLAY INVISIBLE (-6325 5585);
WIRE 16 -1 (-6400 5525)(-7450 5525);
FORCEPROP 2 LAST SIG_NAME SMB_RT_CPU1_P2_ROM_R_SDA
J 0
(-7360 5535);
DISPLAY 0.680851 (-7360 5535);
WIRE 16 -1 (-5200 5525)(-6200 5525);
FORCEPROP 2 LAST SIG_NAME SMB_RT_CPU1_P2_ROM_SDA
J 0
(-6085 5535);
DISPLAY 0.680851 (-6085 5535);
FORCEPROP 2 LASTPROP $XRERR UNIQUE?
J 0
(-6325 5535);
DISPLAY 0.638298 (-6325 5535);
PAINT MONO (-6325 5535);
DISPLAY INVISIBLE (-6325 5535);
WIRE 16 -1 (-4550 5575)(-3900 5575);
FORCEPROP 2 LAST SIG_NAME U20_E2
J 0
(-4335 5585);
DISPLAY 0.680851 (-4335 5585);
FORCEPROP 2 LASTPROP $XRERR UNIQUE?
J 0
(-4575 5585);
DISPLAY 0.638298 (-4575 5585);
PAINT MONO (-4575 5585);
DISPLAY INVISIBLE (-4575 5585);
WIRE 16 -1 (-3900 5575)(-3900 5525);
WIRE 16 -1 (-5600 6125)(-5600 6225);
WIRE 16 -1 (-5600 6225)(-5300 6225);
WIRE 16 -1 (-5300 6225)(-5300 5675);
WIRE 16 -1 (-5300 6225)(-5300 6300);
WIRE 16 -1 (-5300 5675)(-5200 5675);
DOT 1 (-5300 6225);
FORCENOTE
RETIMER EEPRO ADDRESS: 0XA0 (8 BIT) / 0X50 (7 BIT)
(-8150 5125) 0;
DISPLAY LEFT (-8150 5125);
DISPLAY 1.595745 (-8150 5125);
QUIT
